(kicad_pcb
	(version 20260206)
	(generator "pcbnew")
	(generator_version "10.0")
	(general
		(thickness 1.6)
		(legacy_teardrops no)
	)
	(paper "A4")
	(title_block
		(title "Wiwynn_Tioga_Pass_MB.brd")
		(comment 1 "Tioga Pass / footprints 2684-2690 of 4770")
	)
	(layers
		(0 "F.Cu" signal "TOP")
		(4 "In1.Cu" signal "L2GND")
		(6 "In2.Cu" signal "L3")
		(8 "In3.Cu" signal "L4GND")
		(10 "In4.Cu" signal "L5")
		(12 "In5.Cu" signal "L6GND")
		(14 "In6.Cu" signal "L7VCC")
		(16 "In7.Cu" signal "L8VCC")
		(18 "In8.Cu" signal "L9GND")
		(20 "In9.Cu" signal "L10")
		(22 "In10.Cu" signal "L11GND")
		(24 "In11.Cu" signal "L12")
		(26 "In12.Cu" signal "L13GND")
		(2 "B.Cu" signal "BOTTOM")
		(9 "F.Adhes" user "F.Adhesive")
		(11 "B.Adhes" user "B.Adhesive")
		(13 "F.Paste" user "Package Geometry/Pastemask Top")
		(15 "B.Paste" user "Package Geometry/Pastemask Bottom")
		(5 "F.SilkS" user "Ref Des/Silkscreen Top")
		(7 "B.SilkS" user "Ref Des/Silkscreen Bottom")
		(1 "F.Mask" user "Board Geometry/Soldermask Top")
		(3 "B.Mask" user "Board Geometry/Soldermask Bottom")
		(17 "Dwgs.User" user "User.Drawings")
		(19 "Cmts.User" user "User.Comments")
		(21 "Eco1.User" user "User.Eco1")
		(23 "Eco2.User" user "User.Eco2")
		(25 "Edge.Cuts" user "Board Geometry/Outline")
		(27 "Margin" user)
		(31 "F.CrtYd" user "Package Geometry/Place Bound Top")
		(29 "B.CrtYd" user "Package Geometry/Place Bound Bottom")
		(35 "F.Fab" user "Ref Des/Assembly Top")
		(33 "B.Fab" user "Ref Des/Assembly Bottom")
	)
	(footprint ""
		(layer "B.Cu")
		(at 449.199 -116.49202)
		(property "Reference" "C1M17"
			(at 0 0 0)
			(layer "B.SilkS")
			(hide yes)
			(effects
				(font
					(size 1.27 1.27)
				)
				(justify mirror)
			)
		)
		(property "Value" ""
			(at 0 0 0)
			(layer "B.Fab")
			(effects
				(font
					(size 1.27 1.27)
				)
				(justify mirror)
			)
		)
		(duplicate_pad_numbers_are_jumpers no)
		(fp_rect
			(start -0.3048 0.9906)
			(end 0.3048 -0.1016)
			(stroke
				(width 0)
				(type default)
			)
			(fill no)
			(layer "B.CrtYd")
		)
		(fp_line
			(start -0.3048 -0.1016)
			(end 0.3048 -0.1016)
			(stroke
				(width 0.1)
				(type default)
			)
			(layer "B.Fab")
		)
		(fp_line
			(start -0.3048 0.9906)
			(end -0.3048 -0.1016)
			(stroke
				(width 0.1)
				(type default)
			)
			(layer "B.Fab")
		)
		(fp_line
			(start 0.3048 -0.1016)
			(end 0.3048 0.9906)
			(stroke
				(width 0.1)
				(type default)
			)
			(layer "B.Fab")
		)
		(fp_line
			(start 0.3048 0.9906)
			(end -0.3048 0.9906)
			(stroke
				(width 0.1)
				(type default)
			)
			(layer "B.Fab")
		)
		(pad "1" smd rect
			(at 0 0 180)
			(size 0.508 0.508)
			(layers "B.Cu" "B.Mask" "B.Paste")
			(net "P3E_CPU0_PE3_OCP_TXN<10>")
		)
		(pad "2" smd rect
			(at 0 0.889 180)
			(size 0.508 0.508)
			(layers "B.Cu" "B.Mask" "B.Paste")
			(net "P3E_OCP_CPU0_PE3_C_TXN<10>")
		)
		(zone
			(layer "B.Cu")
			(hatch none 0.5)
			(connect_pads
				(clearance 0)
			)
			(min_thickness 0.25)
			(keepout
				(tracks allowed)
				(vias not_allowed)
				(pads allowed)
				(copperpour not_allowed)
				(footprints allowed)
			)
			(placement
				(enabled no)
				(sheetname "")
			)
			(fill
				(thermal_gap 0.5)
				(thermal_bridge_width 0.5)
				(island_removal_mode 0)
			)
			(polygon
				(pts
					(xy 448.945 -115.85702) (xy 449.453 -115.85702) (xy 449.453 -116.23802) (xy 448.945 -116.23802)
				)
			)
		)
		(zone
			(layer "B.Cu")
			(hatch none 0.5)
			(connect_pads
				(clearance 0)
			)
			(min_thickness 0.25)
			(keepout
				(tracks not_allowed)
				(vias allowed)
				(pads allowed)
				(copperpour not_allowed)
				(footprints allowed)
			)
			(placement
				(enabled no)
				(sheetname "")
			)
			(fill
				(thermal_gap 0.5)
				(thermal_bridge_width 0.5)
				(island_removal_mode 0)
			)
			(polygon
				(pts
					(xy 448.945 -115.85702) (xy 449.453 -115.85702) (xy 449.453 -116.23802) (xy 448.945 -116.23802)
				)
			)
		)
	)
	(footprint ""
		(layer "B.Cu")
		(at 440.4233 -147.956016 180)
		(property "Reference" "R25W169"
			(at 0.8382 -0.67818 180)
			(unlocked yes)
			(layer "B.SilkS")
			(effects
				(font
					(size 0.4064 0.254)
					(thickness 0.1524)
				)
				(justify left mirror)
			)
		)
		(property "Value" ""
			(at 0 0 0)
			(layer "B.Fab")
			(effects
				(font
					(size 1.27 1.27)
				)
				(justify mirror)
			)
		)
		(duplicate_pad_numbers_are_jumpers no)
		(fp_poly
			(pts
				(xy 0.2794 -0.1016) (xy -0.2794 -0.1016) (xy -0.2794 0.9906) (xy 0.2794 0.9906)
			)
			(stroke
				(width 0)
				(type default)
			)
			(fill no)
			(layer "B.CrtYd")
		)
		(fp_line
			(start 0.2794 0.9906)
			(end -0.2794 0.9906)
			(stroke
				(width 0.1)
				(type default)
			)
			(layer "B.Fab")
		)
		(fp_line
			(start 0.2794 -0.1016)
			(end 0.2794 0.9906)
			(stroke
				(width 0.1)
				(type default)
			)
			(layer "B.Fab")
		)
		(fp_line
			(start -0.2794 0.9906)
			(end -0.2794 -0.1016)
			(stroke
				(width 0.1)
				(type default)
			)
			(layer "B.Fab")
		)
		(fp_line
			(start -0.2794 -0.1016)
			(end 0.2794 -0.1016)
			(stroke
				(width 0.1)
				(type default)
			)
			(layer "B.Fab")
		)
		(pad "1" smd rect
			(at 0 0)
			(size 0.508 0.508)
			(layers "B.Cu" "B.Mask" "B.Paste")
			(net "JTAG_BMC_TCK1")
		)
		(pad "2" smd rect
			(at 0 0.889)
			(size 0.508 0.508)
			(layers "B.Cu" "B.Mask" "B.Paste")
			(net "GND")
		)
		(zone
			(layer "B.Cu")
			(hatch none 0.5)
			(connect_pads
				(clearance 0)
			)
			(min_thickness 0.25)
			(keepout
				(tracks not_allowed)
				(vias allowed)
				(pads allowed)
				(copperpour not_allowed)
				(footprints allowed)
			)
			(placement
				(enabled no)
				(sheetname "")
			)
			(fill
				(thermal_gap 0.5)
				(thermal_bridge_width 0.5)
				(island_removal_mode 0)
			)
			(polygon
				(pts
					(xy 440.1693 -148.591016) (xy 440.6773 -148.591016) (xy 440.6773 -148.210016) (xy 440.1693 -148.210016)
				)
			)
		)
		(zone
			(layer "B.Cu")
			(hatch none 0.5)
			(connect_pads
				(clearance 0)
			)
			(min_thickness 0.25)
			(keepout
				(tracks allowed)
				(vias not_allowed)
				(pads allowed)
				(copperpour not_allowed)
				(footprints allowed)
			)
			(placement
				(enabled no)
				(sheetname "")
			)
			(fill
				(thermal_gap 0.5)
				(thermal_bridge_width 0.5)
				(island_removal_mode 0)
			)
			(polygon
				(pts
					(xy 440.1693 -148.210016) (xy 440.6773 -148.210016) (xy 440.6773 -148.591016) (xy 440.1693 -148.591016)
				)
			)
		)
	)
	(footprint ""
		(layer "B.Cu")
		(at 377.698 -20.32 180)
		(property "Reference" "RN8F4"
			(at 0.8382 -0.67818 180)
			(unlocked yes)
			(layer "B.SilkS")
			(effects
				(font
					(size 0.4064 0.254)
					(thickness 0.1524)
				)
				(justify left mirror)
			)
		)
		(property "Value" ""
			(at 0 0 0)
			(layer "B.Fab")
			(effects
				(font
					(size 1.27 1.27)
				)
				(justify mirror)
			)
		)
		(duplicate_pad_numbers_are_jumpers no)
		(fp_poly
			(pts
				(xy 0.2794 -0.1016) (xy -0.2794 -0.1016) (xy -0.2794 0.9906) (xy 0.2794 0.9906)
			)
			(stroke
				(width 0)
				(type default)
			)
			(fill no)
			(layer "B.CrtYd")
		)
		(fp_line
			(start 0.2794 0.9906)
			(end -0.2794 0.9906)
			(stroke
				(width 0.1)
				(type default)
			)
			(layer "B.Fab")
		)
		(fp_line
			(start 0.2794 -0.1016)
			(end 0.2794 0.9906)
			(stroke
				(width 0.1)
				(type default)
			)
			(layer "B.Fab")
		)
		(fp_line
			(start -0.2794 0.9906)
			(end -0.2794 -0.1016)
			(stroke
				(width 0.1)
				(type default)
			)
			(layer "B.Fab")
		)
		(fp_line
			(start -0.2794 -0.1016)
			(end 0.2794 -0.1016)
			(stroke
				(width 0.1)
				(type default)
			)
			(layer "B.Fab")
		)
		(pad "1" smd rect
			(at 0 0)
			(size 0.508 0.508)
			(layers "B.Cu" "B.Mask" "B.Paste")
			(net "P3V3_STBY")
		)
		(pad "2" smd rect
			(at 0 0.889)
			(size 0.508 0.508)
			(layers "B.Cu" "B.Mask" "B.Paste")
			(net "PU_TPM_SPI_FLASH_RESET_2_N")
		)
		(zone
			(layer "B.Cu")
			(hatch none 0.5)
			(connect_pads
				(clearance 0)
			)
			(min_thickness 0.25)
			(keepout
				(tracks not_allowed)
				(vias allowed)
				(pads allowed)
				(copperpour not_allowed)
				(footprints allowed)
			)
			(placement
				(enabled no)
				(sheetname "")
			)
			(fill
				(thermal_gap 0.5)
				(thermal_bridge_width 0.5)
				(island_removal_mode 0)
			)
			(polygon
				(pts
					(xy 377.444 -20.955) (xy 377.952 -20.955) (xy 377.952 -20.574) (xy 377.444 -20.574)
				)
			)
		)
		(zone
			(layer "B.Cu")
			(hatch none 0.5)
			(connect_pads
				(clearance 0)
			)
			(min_thickness 0.25)
			(keepout
				(tracks allowed)
				(vias not_allowed)
				(pads allowed)
				(copperpour not_allowed)
				(footprints allowed)
			)
			(placement
				(enabled no)
				(sheetname "")
			)
			(fill
				(thermal_gap 0.5)
				(thermal_bridge_width 0.5)
				(island_removal_mode 0)
			)
			(polygon
				(pts
					(xy 377.444 -20.574) (xy 377.952 -20.574) (xy 377.952 -20.955) (xy 377.444 -20.955)
				)
			)
		)
	)
	(footprint ""
		(layer "B.Cu")
		(at 382.79705 -108.4834 -90)
		(property "Reference" "C3N16"
			(at 0 0 90)
			(layer "B.SilkS")
			(hide yes)
			(effects
				(font
					(size 1.27 1.27)
				)
				(justify mirror)
			)
		)
		(property "Value" ""
			(at 0 0 90)
			(layer "B.Fab")
			(effects
				(font
					(size 1.27 1.27)
				)
				(justify mirror)
			)
		)
		(duplicate_pad_numbers_are_jumpers no)
		(fp_rect
			(start 0.2794 0.9144)
			(end -0.2794 -0.1143)
			(stroke
				(width 0)
				(type default)
			)
			(fill no)
			(layer "B.CrtYd")
		)
		(fp_line
			(start -0.2794 0.9144)
			(end 0.2794 0.9144)
			(stroke
				(width 0.1)
				(type default)
			)
			(layer "B.Fab")
		)
		(fp_line
			(start 0.2794 0.9144)
			(end 0.2794 -0.1143)
			(stroke
				(width 0.1)
				(type default)
			)
			(layer "B.Fab")
		)
		(fp_line
			(start -0.2794 -0.1143)
			(end -0.2794 0.9144)
			(stroke
				(width 0.1)
				(type default)
			)
			(layer "B.Fab")
		)
		(fp_line
			(start 0.2794 -0.1143)
			(end -0.2794 -0.1143)
			(stroke
				(width 0.1)
				(type default)
			)
			(layer "B.Fab")
		)
		(pad "1" smd custom
			(at 0 0 180)
			(size 0.10414 0.10414)
			(layers "B.Cu" "B.Mask" "B.Paste")
			(net "PVNN_PCH_STBY")
			(options
				(clearance outline)
				(anchor circle)
			)
			(primitives
				(gr_poly
					(pts
						(xy -0.20828 -0.08636) (xy -0.20828 0.08636) (xy -0.08636 0.20828) (xy 0.086614 0.20828) (xy 0.20828 0.086614)
						(xy 0.20828 -0.08636) (xy 0.08636 -0.20828) (xy -0.08636 -0.20828)
					)
					(width 0)
					(fill yes)
				)
			)
		)
		(pad "2" smd custom
			(at 0 0.8001 180)
			(size 0.10414 0.10414)
			(layers "B.Cu" "B.Mask" "B.Paste")
			(net "GND")
			(options
				(clearance outline)
				(anchor circle)
			)
			(primitives
				(gr_poly
					(pts
						(xy -0.20828 -0.08636) (xy -0.20828 0.08636) (xy -0.08636 0.20828) (xy 0.086614 0.20828) (xy 0.20828 0.086614)
						(xy 0.20828 -0.08636) (xy 0.08636 -0.20828) (xy -0.08636 -0.20828)
					)
					(width 0)
					(fill yes)
				)
			)
		)
		(zone
			(layer "B.Cu")
			(hatch none 0.5)
			(connect_pads
				(clearance 0)
			)
			(min_thickness 0.25)
			(keepout
				(tracks allowed)
				(vias not_allowed)
				(pads allowed)
				(copperpour not_allowed)
				(footprints allowed)
			)
			(placement
				(enabled no)
				(sheetname "")
			)
			(fill
				(thermal_gap 0.5)
				(thermal_bridge_width 0.5)
				(island_removal_mode 0)
			)
			(polygon
				(pts
					(xy 382.5875 -108.39577) (xy 382.2065 -108.39577) (xy 382.2065 -108.57103) (xy 382.5875 -108.571284)
				)
			)
		)
		(zone
			(layer "B.Cu")
			(hatch none 0.5)
			(connect_pads
				(clearance 0)
			)
			(min_thickness 0.25)
			(keepout
				(tracks not_allowed)
				(vias allowed)
				(pads allowed)
				(copperpour not_allowed)
				(footprints allowed)
			)
			(placement
				(enabled no)
				(sheetname "")
			)
			(fill
				(thermal_gap 0.5)
				(thermal_bridge_width 0.5)
				(island_removal_mode 0)
			)
			(polygon
				(pts
					(xy 382.5875 -108.39577) (xy 382.2065 -108.39577) (xy 382.2065 -108.57103) (xy 382.5875 -108.571284)
				)
			)
		)
	)
	(footprint ""
		(layer "B.Cu")
		(at 28.0924 2.1336 -90)
		(property "Reference" "C9U11"
			(at 0 0 90)
			(layer "B.SilkS")
			(hide yes)
			(effects
				(font
					(size 1.27 1.27)
				)
				(justify mirror)
			)
		)
		(property "Value" ""
			(at 0 0 90)
			(layer "B.Fab")
			(effects
				(font
					(size 1.27 1.27)
				)
				(justify mirror)
			)
		)
		(duplicate_pad_numbers_are_jumpers no)
		(fp_rect
			(start 0.7239 -0.2159)
			(end -0.7239 1.9939)
			(stroke
				(width 0)
				(type default)
			)
			(fill no)
			(layer "B.CrtYd")
		)
		(fp_line
			(start -0.7239 1.9939)
			(end -0.7239 -0.2159)
			(stroke
				(width 0.1)
				(type default)
			)
			(layer "B.Fab")
		)
		(fp_line
			(start 0.7239 1.9939)
			(end -0.7239 1.9939)
			(stroke
				(width 0.1)
				(type default)
			)
			(layer "B.Fab")
		)
		(fp_line
			(start -0.7239 -0.2159)
			(end 0.7239 -0.2159)
			(stroke
				(width 0.1)
				(type default)
			)
			(layer "B.Fab")
		)
		(fp_line
			(start 0.7239 -0.2159)
			(end 0.7239 1.9939)
			(stroke
				(width 0.1)
				(type default)
			)
			(layer "B.Fab")
		)
		(pad "1" smd rect
			(at 0 0 90)
			(size 1.27 1.016)
			(layers "B.Cu" "B.Mask" "B.Paste")
			(net "P12V_NVDIMM_GHJ")
		)
		(pad "2" smd rect
			(at 0 1.778 90)
			(size 1.27 1.016)
			(layers "B.Cu" "B.Mask" "B.Paste")
			(net "GND")
		)
		(zone
			(layer "B.Cu")
			(hatch none 0.5)
			(connect_pads
				(clearance 0)
			)
			(min_thickness 0.25)
			(keepout
				(tracks not_allowed)
				(vias allowed)
				(pads allowed)
				(copperpour not_allowed)
				(footprints allowed)
			)
			(placement
				(enabled no)
				(sheetname "")
			)
			(fill
				(thermal_gap 0.5)
				(thermal_bridge_width 0.5)
				(island_removal_mode 0)
			)
			(polygon
				(pts
					(xy 27.5844 2.7686) (xy 27.5844 1.4986) (xy 26.8224 1.4986) (xy 26.8224 2.7686)
				)
			)
		)
	)
	(footprint ""
		(layer "B.Cu")
		(at 402.3995 -42.164 -90)
		(property "Reference" "R25W75"
			(at 0.8382 -0.67818 270)
			(unlocked yes)
			(layer "B.SilkS")
			(effects
				(font
					(size 0.4064 0.254)
					(thickness 0.1524)
				)
				(justify left mirror)
			)
		)
		(property "Value" ""
			(at 0 0 90)
			(layer "B.Fab")
			(effects
				(font
					(size 1.27 1.27)
				)
				(justify mirror)
			)
		)
		(duplicate_pad_numbers_are_jumpers no)
		(fp_poly
			(pts
				(xy 0.2794 -0.1016) (xy -0.2794 -0.1016) (xy -0.2794 0.9906) (xy 0.2794 0.9906)
			)
			(stroke
				(width 0)
				(type default)
			)
			(fill no)
			(layer "B.CrtYd")
		)
		(fp_line
			(start -0.2794 0.9906)
			(end -0.2794 -0.1016)
			(stroke
				(width 0.1)
				(type default)
			)
			(layer "B.Fab")
		)
		(fp_line
			(start 0.2794 0.9906)
			(end -0.2794 0.9906)
			(stroke
				(width 0.1)
				(type default)
			)
			(layer "B.Fab")
		)
		(fp_line
			(start -0.2794 -0.1016)
			(end 0.2794 -0.1016)
			(stroke
				(width 0.1)
				(type default)
			)
			(layer "B.Fab")
		)
		(fp_line
			(start 0.2794 -0.1016)
			(end 0.2794 0.9906)
			(stroke
				(width 0.1)
				(type default)
			)
			(layer "B.Fab")
		)
		(pad "1" smd rect
			(at 0 0 90)
			(size 0.508 0.508)
			(layers "B.Cu" "B.Mask" "B.Paste")
			(net "FM_CPU1_FIVR_FAULT_LVT3_R_N")
		)
		(pad "2" smd rect
			(at 0 0.889 90)
			(size 0.508 0.508)
			(layers "B.Cu" "B.Mask" "B.Paste")
			(net "FM_CPU1_FIVR_FAULT_LVT3_N")
		)
		(zone
			(layer "B.Cu")
			(hatch none 0.5)
			(connect_pads
				(clearance 0)
			)
			(min_thickness 0.25)
			(keepout
				(tracks not_allowed)
				(vias allowed)
				(pads allowed)
				(copperpour not_allowed)
				(footprints allowed)
			)
			(placement
				(enabled no)
				(sheetname "")
			)
			(fill
				(thermal_gap 0.5)
				(thermal_bridge_width 0.5)
				(island_removal_mode 0)
			)
			(polygon
				(pts
					(xy 401.7645 -41.91) (xy 401.7645 -42.418) (xy 402.1455 -42.418) (xy 402.1455 -41.91)
				)
			)
		)
		(zone
			(layer "B.Cu")
			(hatch none 0.5)
			(connect_pads
				(clearance 0)
			)
			(min_thickness 0.25)
			(keepout
				(tracks allowed)
				(vias not_allowed)
				(pads allowed)
				(copperpour not_allowed)
				(footprints allowed)
			)
			(placement
				(enabled no)
				(sheetname "")
			)
			(fill
				(thermal_gap 0.5)
				(thermal_bridge_width 0.5)
				(island_removal_mode 0)
			)
			(polygon
				(pts
					(xy 402.1455 -41.91) (xy 402.1455 -42.418) (xy 401.7645 -42.418) (xy 401.7645 -41.91)
				)
			)
		)
	)
	(footprint ""
		(layer "B.Cu")
		(at 186.015376 -59.243722 180)
		(property "Reference" "C22W15"
			(at 0 0 0)
			(layer "B.SilkS")
			(hide yes)
			(effects
				(font
					(size 1.27 1.27)
				)
				(justify mirror)
			)
		)
		(property "Value" "*"
			(at 0.0762 -6.2357 180)
			(unlocked yes)
			(layer "B.Fab")
			(hide yes)
			(effects
				(font
					(size 1.27 1.016)
					(thickness 0.1524)
				)
				(justify mirror)
			)
		)
		(property "Device Type" "SC22U16V5MX-4-GP_SMD-BCG5-SC22A"
			(at 0.0762 -8.2677 180)
			(unlocked yes)
			(layer "B.Fab")
			(hide yes)
			(effects
				(font
					(size 1.27 1.016)
					(thickness 0.1524)
				)
				(justify mirror)
			)
		)
		(duplicate_pad_numbers_are_jumpers no)
		(fp_line
			(start -0.635 0)
			(end 0.635 0)
			(stroke
				(width 0.508)
				(type default)
			)
			(layer "B.SilkS")
		)
		(fp_rect
			(start 0.9652 1.778)
			(end -0.9652 -1.778)
			(stroke
				(width 0)
				(type default)
			)
			(fill no)
			(layer "B.CrtYd")
		)
		(fp_poly
			(pts
				(xy 0.9652 -1.778) (xy -0.9652 -1.778) (xy -0.9652 1.778) (xy 0.9652 1.778)
			)
			(stroke
				(width 0)
				(type default)
			)
			(fill no)
			(layer "B.Fab")
		)
		(pad "1" smd rect
			(at 0 -0.9652)
			(size 1.397 1.143)
			(layers "B.Cu" "B.Mask" "B.Paste")
			(net "VR_FET_SW_P12V_STBY_PVCCIN_CPU0")
		)
		(pad "2" smd rect
			(at 0 0.9652)
			(size 1.397 1.143)
			(layers "B.Cu" "B.Mask" "B.Paste")
			(net "GND")
		)
	)
)
